(kicad_pcb
	(version 20260206)
	(generator "pcbnew")
	(generator_version "10.0")
	(general
		(thickness 1.6)
		(legacy_teardrops no)
	)
	(paper "A4")
	(title_block
		(title "03242023_DA0F0TMBIJ0_F0T_Motherboard_J_brd_V01_OCP.brd")
		(comment 1 "Grand Teton / footprints 33-36 of 6105")
	)
	(layers
		(0 "F.Cu" signal "TOP")
		(4 "In1.Cu" signal "GND")
		(6 "In2.Cu" signal "IN1")
		(8 "In3.Cu" signal "GND1")
		(10 "In4.Cu" signal "IN2")
		(12 "In5.Cu" signal "GND2")
		(14 "In6.Cu" signal "IN3")
		(16 "In7.Cu" signal "GND3")
		(18 "In8.Cu" signal "VCC")
		(20 "In9.Cu" signal "VCC1")
		(22 "In10.Cu" signal "GND4")
		(24 "In11.Cu" signal "IN4")
		(26 "In12.Cu" signal "GND5")
		(28 "In13.Cu" signal "IN5")
		(30 "In14.Cu" signal "GND6")
		(32 "In15.Cu" signal "IN6")
		(34 "In16.Cu" signal "GND7")
		(2 "B.Cu" signal "BOTTOM")
		(9 "F.Adhes" user "F.Adhesive")
		(11 "B.Adhes" user "B.Adhesive")
		(13 "F.Paste" user "Package Geometry/Pastemask Top")
		(15 "B.Paste" user "Package Geometry/Pastemask Bottom")
		(5 "F.SilkS" user "Ref Des/Silkscreen Top")
		(7 "B.SilkS" user "Ref Des/Silkscreen Bottom")
		(1 "F.Mask" user "Board Geometry/Soldermask Top")
		(3 "B.Mask" user "Board Geometry/Soldermask Bottom")
		(17 "Dwgs.User" user "User.Drawings")
		(19 "Cmts.User" user "User.Comments")
		(21 "Eco1.User" user "User.Eco1")
		(23 "Eco2.User" user "User.Eco2")
		(25 "Edge.Cuts" user "Board Geometry/Outline")
		(27 "Margin" user)
		(31 "F.CrtYd" user "Package Geometry/Place Bound Top")
		(29 "B.CrtYd" user "Package Geometry/Place Bound Bottom")
		(35 "F.Fab" user "Ref Des/Assembly Top")
		(33 "B.Fab" user "Ref Des/Assembly Bottom")
	)
	(footprint ""
		(layer "F.Cu")
		(at 118.542816 -256.6543 -90)
		(property "Reference" "C248"
			(at 0 0 270)
			(layer "F.SilkS")
			(hide yes)
			(effects
				(font
					(size 1.27 1.27)
				)
			)
		)
		(property "Value" ""
			(at 0 0 270)
			(layer "F.Fab")
			(effects
				(font
					(size 1.27 1.27)
				)
			)
		)
		(duplicate_pad_numbers_are_jumpers no)
		(fp_line
			(start -0.7874 0.4064)
			(end -0.7874 -0.4064)
			(stroke
				(width 0.1524)
				(type default)
			)
			(layer "F.SilkS")
		)
		(fp_line
			(start 0.7874 0.4064)
			(end -0.7874 0.4064)
			(stroke
				(width 0.1524)
				(type default)
			)
			(layer "F.SilkS")
		)
		(fp_line
			(start -0.7874 -0.4064)
			(end 0.7874 -0.4064)
			(stroke
				(width 0.1524)
				(type default)
			)
			(layer "F.SilkS")
		)
		(fp_line
			(start 0.7874 -0.4064)
			(end 0.7874 0.4064)
			(stroke
				(width 0.1524)
				(type default)
			)
			(layer "F.SilkS")
		)
		(fp_line
			(start -0.67945 0.3048)
			(end -0.67945 -0.305054)
			(stroke
				(width 0.1)
				(type default)
			)
			(layer "F.Fab")
		)
		(fp_line
			(start -0.12065 0.3048)
			(end -0.67945 0.3048)
			(stroke
				(width 0.1)
				(type default)
			)
			(layer "F.Fab")
		)
		(fp_line
			(start 0.120396 0.3048)
			(end 0.120396 0.2794)
			(stroke
				(width 0.1)
				(type default)
			)
			(layer "F.Fab")
		)
		(fp_line
			(start 0.67945 0.3048)
			(end 0.120396 0.3048)
			(stroke
				(width 0.1)
				(type default)
			)
			(layer "F.Fab")
		)
		(fp_line
			(start -0.12065 0.2794)
			(end -0.12065 0.3048)
			(stroke
				(width 0.1)
				(type default)
			)
			(layer "F.Fab")
		)
		(fp_line
			(start 0.120396 0.2794)
			(end -0.12065 0.2794)
			(stroke
				(width 0.1)
				(type default)
			)
			(layer "F.Fab")
		)
		(fp_line
			(start -0.12065 -0.2794)
			(end 0.12065 -0.2794)
			(stroke
				(width 0.1)
				(type default)
			)
			(layer "F.Fab")
		)
		(fp_line
			(start 0.12065 -0.2794)
			(end 0.12065 -0.3048)
			(stroke
				(width 0.1)
				(type default)
			)
			(layer "F.Fab")
		)
		(fp_line
			(start 0.12065 -0.3048)
			(end 0.67945 -0.3048)
			(stroke
				(width 0.1)
				(type default)
			)
			(layer "F.Fab")
		)
		(fp_line
			(start 0.67945 -0.3048)
			(end 0.67945 0.3048)
			(stroke
				(width 0.1)
				(type default)
			)
			(layer "F.Fab")
		)
		(fp_line
			(start -0.67945 -0.305054)
			(end -0.12065 -0.305054)
			(stroke
				(width 0.1)
				(type default)
			)
			(layer "F.Fab")
		)
		(fp_line
			(start -0.12065 -0.305054)
			(end -0.12065 -0.2794)
			(stroke
				(width 0.1)
				(type default)
			)
			(layer "F.Fab")
		)
		(pad "1" smd circle
			(at -0.40005 0 270)
			(size 0 0)
			(layers "F.Cu" "F.Mask" "F.Paste")
			(net "PVCCIN_CPU1")
		)
		(pad "2" smd circle
			(at 0.40005 0 270)
			(size 0 0)
			(layers "F.Cu" "F.Mask" "F.Paste")
			(net "GND")
		)
	)
	(footprint ""
		(layer "F.Cu")
		(at 122.301 -75.021948 90)
		(property "Reference" "R2506"
			(at 0 0 90)
			(layer "F.SilkS")
			(hide yes)
			(effects
				(font
					(size 1.27 1.27)
				)
			)
		)
		(property "Value" ""
			(at 0 0 90)
			(layer "F.Fab")
			(effects
				(font
					(size 1.27 1.27)
				)
			)
		)
		(duplicate_pad_numbers_are_jumpers no)
		(fp_line
			(start 0.7874 -0.4064)
			(end 0.7874 0.4064)
			(stroke
				(width 0.1524)
				(type default)
			)
			(layer "F.SilkS")
		)
		(fp_line
			(start -0.7874 -0.4064)
			(end 0.7874 -0.4064)
			(stroke
				(width 0.1524)
				(type default)
			)
			(layer "F.SilkS")
		)
		(fp_line
			(start 0.7874 0.4064)
			(end -0.7874 0.4064)
			(stroke
				(width 0.1524)
				(type default)
			)
			(layer "F.SilkS")
		)
		(fp_line
			(start -0.7874 0.4064)
			(end -0.7874 -0.4064)
			(stroke
				(width 0.1524)
				(type default)
			)
			(layer "F.SilkS")
		)
		(fp_line
			(start -0.12065 -0.305054)
			(end -0.12065 -0.2794)
			(stroke
				(width 0.1)
				(type default)
			)
			(layer "F.Fab")
		)
		(fp_line
			(start -0.67945 -0.305054)
			(end -0.12065 -0.305054)
			(stroke
				(width 0.1)
				(type default)
			)
			(layer "F.Fab")
		)
		(fp_line
			(start 0.67945 -0.3048)
			(end 0.67945 0.3048)
			(stroke
				(width 0.1)
				(type default)
			)
			(layer "F.Fab")
		)
		(fp_line
			(start 0.12065 -0.3048)
			(end 0.67945 -0.3048)
			(stroke
				(width 0.1)
				(type default)
			)
			(layer "F.Fab")
		)
		(fp_line
			(start 0.12065 -0.2794)
			(end 0.12065 -0.3048)
			(stroke
				(width 0.1)
				(type default)
			)
			(layer "F.Fab")
		)
		(fp_line
			(start -0.12065 -0.2794)
			(end 0.12065 -0.2794)
			(stroke
				(width 0.1)
				(type default)
			)
			(layer "F.Fab")
		)
		(fp_line
			(start 0.120396 0.2794)
			(end -0.12065 0.2794)
			(stroke
				(width 0.1)
				(type default)
			)
			(layer "F.Fab")
		)
		(fp_line
			(start -0.12065 0.2794)
			(end -0.12065 0.3048)
			(stroke
				(width 0.1)
				(type default)
			)
			(layer "F.Fab")
		)
		(fp_line
			(start 0.67945 0.3048)
			(end 0.120396 0.3048)
			(stroke
				(width 0.1)
				(type default)
			)
			(layer "F.Fab")
		)
		(fp_line
			(start 0.120396 0.3048)
			(end 0.120396 0.2794)
			(stroke
				(width 0.1)
				(type default)
			)
			(layer "F.Fab")
		)
		(fp_line
			(start -0.12065 0.3048)
			(end -0.67945 0.3048)
			(stroke
				(width 0.1)
				(type default)
			)
			(layer "F.Fab")
		)
		(fp_line
			(start -0.67945 0.3048)
			(end -0.67945 -0.305054)
			(stroke
				(width 0.1)
				(type default)
			)
			(layer "F.Fab")
		)
		(pad "1" smd circle
			(at -0.40005 0 90)
			(size 0 0)
			(layers "F.Cu" "F.Mask" "F.Paste")
			(net "P3V3_AUX")
		)
		(pad "2" smd circle
			(at 0.40005 0 90)
			(size 0 0)
			(layers "F.Cu" "F.Mask" "F.Paste")
			(net "JTAG_BMC_DBP_TMS")
		)
	)
	(footprint ""
		(layer "F.Cu")
		(at 257.85953 -51.669442)
		(property "Reference" "PC2281"
			(at 0 0 0)
			(layer "F.SilkS")
			(hide yes)
			(effects
				(font
					(size 1.27 1.27)
				)
			)
		)
		(property "Value" ""
			(at 0 0 0)
			(layer "F.Fab")
			(effects
				(font
					(size 1.27 1.27)
				)
			)
		)
		(duplicate_pad_numbers_are_jumpers no)
		(fp_line
			(start -0.7874 -0.4064)
			(end 0.7874 -0.4064)
			(stroke
				(width 0.1524)
				(type default)
			)
			(layer "F.SilkS")
		)
		(fp_line
			(start -0.7874 0.4064)
			(end -0.7874 -0.4064)
			(stroke
				(width 0.1524)
				(type default)
			)
			(layer "F.SilkS")
		)
		(fp_line
			(start 0.7874 -0.4064)
			(end 0.7874 0.4064)
			(stroke
				(width 0.1524)
				(type default)
			)
			(layer "F.SilkS")
		)
		(fp_line
			(start 0.7874 0.4064)
			(end -0.7874 0.4064)
			(stroke
				(width 0.1524)
				(type default)
			)
			(layer "F.SilkS")
		)
		(fp_line
			(start -0.67945 -0.305054)
			(end -0.12065 -0.305054)
			(stroke
				(width 0.1)
				(type default)
			)
			(layer "F.Fab")
		)
		(fp_line
			(start -0.67945 0.3048)
			(end -0.67945 -0.305054)
			(stroke
				(width 0.1)
				(type default)
			)
			(layer "F.Fab")
		)
		(fp_line
			(start -0.12065 -0.305054)
			(end -0.12065 -0.2794)
			(stroke
				(width 0.1)
				(type default)
			)
			(layer "F.Fab")
		)
		(fp_line
			(start -0.12065 -0.2794)
			(end 0.12065 -0.2794)
			(stroke
				(width 0.1)
				(type default)
			)
			(layer "F.Fab")
		)
		(fp_line
			(start -0.12065 0.2794)
			(end -0.12065 0.3048)
			(stroke
				(width 0.1)
				(type default)
			)
			(layer "F.Fab")
		)
		(fp_line
			(start -0.12065 0.3048)
			(end -0.67945 0.3048)
			(stroke
				(width 0.1)
				(type default)
			)
			(layer "F.Fab")
		)
		(fp_line
			(start 0.120396 0.2794)
			(end -0.12065 0.2794)
			(stroke
				(width 0.1)
				(type default)
			)
			(layer "F.Fab")
		)
		(fp_line
			(start 0.120396 0.3048)
			(end 0.120396 0.2794)
			(stroke
				(width 0.1)
				(type default)
			)
			(layer "F.Fab")
		)
		(fp_line
			(start 0.12065 -0.3048)
			(end 0.67945 -0.3048)
			(stroke
				(width 0.1)
				(type default)
			)
			(layer "F.Fab")
		)
		(fp_line
			(start 0.12065 -0.2794)
			(end 0.12065 -0.3048)
			(stroke
				(width 0.1)
				(type default)
			)
			(layer "F.Fab")
		)
		(fp_line
			(start 0.67945 -0.3048)
			(end 0.67945 0.3048)
			(stroke
				(width 0.1)
				(type default)
			)
			(layer "F.Fab")
		)
		(fp_line
			(start 0.67945 0.3048)
			(end 0.120396 0.3048)
			(stroke
				(width 0.1)
				(type default)
			)
			(layer "F.Fab")
		)
		(pad "1" smd circle
			(at -0.40005 0)
			(size 0 0)
			(layers "F.Cu" "F.Mask" "F.Paste")
			(net "P12V_E1S_SS_0")
		)
		(pad "2" smd circle
			(at 0.40005 0)
			(size 0 0)
			(layers "F.Cu" "F.Mask" "F.Paste")
			(net "GND")
		)
	)
	(footprint ""
		(layer "F.Cu")
		(at 117.526816 -244.032024 90)
		(property "Reference" "C274"
			(at 0 0 90)
			(layer "F.SilkS")
			(hide yes)
			(effects
				(font
					(size 1.27 1.27)
				)
			)
		)
		(property "Value" ""
			(at 0 0 90)
			(layer "F.Fab")
			(effects
				(font
					(size 1.27 1.27)
				)
			)
		)
		(duplicate_pad_numbers_are_jumpers no)
		(fp_line
			(start 0.7874 -0.4064)
			(end 0.7874 0.4064)
			(stroke
				(width 0.1524)
				(type default)
			)
			(layer "F.SilkS")
		)
		(fp_line
			(start -0.7874 -0.4064)
			(end 0.7874 -0.4064)
			(stroke
				(width 0.1524)
				(type default)
			)
			(layer "F.SilkS")
		)
		(fp_line
			(start 0.7874 0.4064)
			(end -0.7874 0.4064)
			(stroke
				(width 0.1524)
				(type default)
			)
			(layer "F.SilkS")
		)
		(fp_line
			(start -0.7874 0.4064)
			(end -0.7874 -0.4064)
			(stroke
				(width 0.1524)
				(type default)
			)
			(layer "F.SilkS")
		)
		(fp_line
			(start -0.12065 -0.305054)
			(end -0.12065 -0.2794)
			(stroke
				(width 0.1)
				(type default)
			)
			(layer "F.Fab")
		)
		(fp_line
			(start -0.67945 -0.305054)
			(end -0.12065 -0.305054)
			(stroke
				(width 0.1)
				(type default)
			)
			(layer "F.Fab")
		)
		(fp_line
			(start 0.67945 -0.3048)
			(end 0.67945 0.3048)
			(stroke
				(width 0.1)
				(type default)
			)
			(layer "F.Fab")
		)
		(fp_line
			(start 0.12065 -0.3048)
			(end 0.67945 -0.3048)
			(stroke
				(width 0.1)
				(type default)
			)
			(layer "F.Fab")
		)
		(fp_line
			(start 0.12065 -0.2794)
			(end 0.12065 -0.3048)
			(stroke
				(width 0.1)
				(type default)
			)
			(layer "F.Fab")
		)
		(fp_line
			(start -0.12065 -0.2794)
			(end 0.12065 -0.2794)
			(stroke
				(width 0.1)
				(type default)
			)
			(layer "F.Fab")
		)
		(fp_line
			(start 0.120396 0.2794)
			(end -0.12065 0.2794)
			(stroke
				(width 0.1)
				(type default)
			)
			(layer "F.Fab")
		)
		(fp_line
			(start -0.12065 0.2794)
			(end -0.12065 0.3048)
			(stroke
				(width 0.1)
				(type default)
			)
			(layer "F.Fab")
		)
		(fp_line
			(start 0.67945 0.3048)
			(end 0.120396 0.3048)
			(stroke
				(width 0.1)
				(type default)
			)
			(layer "F.Fab")
		)
		(fp_line
			(start 0.120396 0.3048)
			(end 0.120396 0.2794)
			(stroke
				(width 0.1)
				(type default)
			)
			(layer "F.Fab")
		)
		(fp_line
			(start -0.12065 0.3048)
			(end -0.67945 0.3048)
			(stroke
				(width 0.1)
				(type default)
			)
			(layer "F.Fab")
		)
		(fp_line
			(start -0.67945 0.3048)
			(end -0.67945 -0.305054)
			(stroke
				(width 0.1)
				(type default)
			)
			(layer "F.Fab")
		)
		(pad "1" smd circle
			(at -0.40005 0 90)
			(size 0 0)
			(layers "F.Cu" "F.Mask" "F.Paste")
			(net "PVCCIN_CPU1")
		)
		(pad "2" smd circle
			(at 0.40005 0 90)
			(size 0 0)
			(layers "F.Cu" "F.Mask" "F.Paste")
			(net "GND")
		)
	)
)
